#ISCELL
  mstr_misc dns *
  *
#ISCELL
  pure_quanta quanta_title_block_c *
  *
#ISCELL
  standard offpage *
  page192_i1
#ISCELL
  pure_quanta_power vcc_core *
  page192_i10
#ISCELL
  standard offpage *
  page192_i100
#ISCELL
  standard offpage *
  page192_i101
#ISCELL
  standard offpage *
  page192_i102
#ISCELL
  standard offpage *
  page192_i103
#ISCELL
  standard offpage *
  page192_i104
#ISCELL
  standard offpage *
  page192_i105
#ISCELL
  standard offpage *
  page192_i106
#ISCELL
  standard offpage *
  page192_i107
#ISCELL
  standard offpage *
  page192_i108
#ISCELL
  pure_quanta_power universal_gnd *
  page192_i109
#ISCELL
  pure_quanta_power vcc_core *
  page192_i11
#ISCELL
  pure_quanta_power universal_gnd *
  page192_i110
#ISCELL
  standard offpage *
  page192_i111
#ISCELL
  standard offpage *
  page192_i112
#ISCELL
  standard offpage *
  page192_i113
#ISCELL
  standard offpage *
  page192_i114
#ISCELL
  standard offpage *
  page192_i115
#ISCELL
  standard offpage *
  page192_i116
#ISCELL
  standard offpage *
  page192_i117
#ISCELL
  standard offpage *
  page192_i118
#ISCELL
  standard offpage *
  page192_i119
#CELL
  pure_quanta q_res *
  page192_i12
#ISCELL
  standard offpage *
  page192_i120
#ISCELL
  standard offpage *
  page192_i121
#ISCELL
  standard offpage *
  page192_i122
#ISCELL
  standard offpage *
  page192_i123
#CELL
  pure_quanta q_res *
  page192_i124
#ISCELL
  pure_quanta_power vcc_core *
  page192_i125
#ISCELL
  standard offpage *
  page192_i126
#CELL
  pure_quanta q_res *
  page192_i127
#CELL
  pure_quanta raa229620gnpha0 *
  page192_i128
#CELL
  pure_quanta mosfet_pch_gds_esd_protected *
  page192_i13
#CELL
  pure_quanta q_res *
  page192_i130
#CELL
  pure_quanta q_cap *
  page192_i131
#ISCELL
  pure_quanta_power universal_gnd *
  page192_i132
#CELL
  pure_quanta q_cap *
  page192_i133
#ISCELL
  pure_quanta_power universal_gnd *
  page192_i134
#ISCELL
  pure_quanta_power universal_gnd *
  page192_i135
#CELL
  pure_quanta q_cap *
  page192_i136
#CELL
  pure_quanta q_res *
  page192_i137
#CELL
  pure_quanta q_res *
  page192_i138
#ISCELL
  standard offpage *
  page192_i14
#ISCELL
  standard offpage *
  page192_i15
#ISCELL
  standard offpage *
  page192_i16
#CELL
  pure_quanta q_res *
  page192_i17
#ISCELL
  pure_quanta_power vcc_core *
  page192_i18
#CELL
  pure_quanta q_res *
  page192_i19
#CELL
  pure_quanta q_res *
  page192_i2
#ISCELL
  standard offpage *
  page192_i20
#ISCELL
  standard offpage *
  page192_i21
#CELL
  pure_quanta q_res *
  page192_i22
#CELL
  pure_quanta q_res *
  page192_i23
#ISCELL
  standard offpage *
  page192_i24
#ISCELL
  standard offpage *
  page192_i25
#ISCELL
  standard offpage *
  page192_i26
#ISCELL
  standard offpage *
  page192_i27
#ISCELL
  pure_quanta_power universal_gnd *
  page192_i28
#CELL
  pure_quanta q_res *
  page192_i29
#CELL
  pure_quanta q_cap *
  page192_i3
#CELL
  pure_quanta q_res *
  page192_i30
#CELL
  pure_quanta q_cap *
  page192_i31
#CELL
  pure_quanta q_cap *
  page192_i32
#CELL
  pure_quanta q_cap *
  page192_i33
#CELL
  pure_quanta q_res *
  page192_i34
#ISCELL
  standard offpage *
  page192_i35
#ISCELL
  standard offpage *
  page192_i36
#ISCELL
  standard offpage *
  page192_i37
#CELL
  pure_quanta q_res *
  page192_i38
#ISCELL
  pure_quanta_power vcc_core *
  page192_i39
#ISCELL
  pure_quanta_power universal_gnd *
  page192_i4
#CELL
  pure_quanta q_res *
  page192_i40
#CELL
  pure_quanta q_res *
  page192_i41
#CELL
  pure_quanta q_res *
  page192_i42
#ISCELL
  standard offpage *
  page192_i43
#ISCELL
  standard offpage *
  page192_i44
#ISCELL
  pure_quanta_power vcc_core *
  page192_i45
#ISCELL
  pure_quanta_power universal_gnd *
  page192_i46
#CELL
  pure_quanta q_cap *
  page192_i47
#ISCELL
  pure_quanta_power vcc_core *
  page192_i48
#CELL
  pure_quanta q_res *
  page192_i49
#ISCELL
  standard offpage *
  page192_i5
#CELL
  pure_quanta q_res *
  page192_i50
#CELL
  pure_quanta q_res *
  page192_i51
#CELL
  pure_quanta q_cap *
  page192_i52
#ISCELL
  pure_quanta_power vcc_core *
  page192_i53
#ISCELL
  pure_quanta_power universal_gnd *
  page192_i54
#CELL
  pure_quanta q_res *
  page192_i55
#CELL
  pure_quanta q_cap *
  page192_i56
#ISCELL
  pure_quanta_power universal_gnd *
  page192_i57
#ISCELL
  pure_quanta_power universal_gnd *
  page192_i58
#ISCELL
  pure_quanta_power universal_gnd *
  page192_i59
#CELL
  pure_quanta mosfet_n *
  page192_i6
#CELL
  pure_quanta q_cap *
  page192_i60
#ISCELL
  pure_quanta_power universal_gnd *
  page192_i61
#ISCELL
  pure_quanta_power universal_gnd *
  page192_i62
#ISCELL
  pure_quanta_power vcc_core *
  page192_i63
#CELL
  pure_quanta q_res *
  page192_i64
#CELL
  pure_quanta q_res *
  page192_i65
#CELL
  pure_quanta q_res *
  page192_i66
#CELL
  pure_quanta q_cap *
  page192_i67
#ISCELL
  pure_quanta_power vcc_core *
  page192_i68
#CELL
  pure_quanta q_res *
  page192_i69
#ISCELL
  pure_quanta_power universal_gnd *
  page192_i7
#ISCELL
  pure_quanta_power universal_gnd *
  page192_i70
#CELL
  pure_quanta q_res *
  page192_i71
#ISCELL
  pure_quanta_power universal_gnd *
  page192_i72
#CELL
  pure_quanta q_cap *
  page192_i73
#ISCELL
  pure_quanta_power universal_gnd *
  page192_i74
#CELL
  pure_quanta q_cap *
  page192_i75
#CELL
  pure_quanta q_res *
  page192_i76
#CELL
  pure_quanta q_res *
  page192_i77
#ISCELL
  pure_quanta_power vcc_core *
  page192_i78
#CELL
  pure_quanta q_cap *
  page192_i79
#CELL
  pure_quanta q_res *
  page192_i8
#CELL
  pure_quanta q_res *
  page192_i80
#CELL
  pure_quanta q_res *
  page192_i81
#CELL
  pure_quanta q_res *
  page192_i82
#CELL
  pure_quanta q_res *
  page192_i83
#CELL
  pure_quanta q_res *
  page192_i84
#CELL
  pure_quanta q_cap *
  page192_i85
#ISCELL
  pure_quanta_power universal_gnd *
  page192_i86
#CELL
  pure_quanta q_res *
  page192_i87
#CELL
  pure_quanta q_res *
  page192_i88
#CELL
  pure_quanta q_res *
  page192_i89
#CELL
  pure_quanta q_res *
  page192_i9
#CELL
  pure_quanta q_cap *
  page192_i90
#ISCELL
  pure_quanta_power universal_gnd *
  page192_i91
#ISCELL
  pure_quanta_power universal_gnd *
  page192_i92
#CELL
  pure_quanta q_cap *
  page192_i93
#ISCELL
  pure_quanta_power universal_gnd *
  page192_i94
#CELL
  pure_quanta q_cap *
  page192_i95
#ISCELL
  pure_quanta_power universal_gnd *
  page192_i96
#CELL
  pure_quanta q_cap *
  page192_i97
#ISCELL
  pure_quanta_power universal_gnd *
  page192_i98
#CELL
  pure_quanta q_cap *
  page192_i99
